# S9S_MB_2U (Grand Teton) — schematic netlist excerpt (pin names and nets, part order shuffled) for the footprints in the layout excerpt that follows; sources: Cadence DE-HDL packaged netlist, KiCad conversion of 03242023_DA0F0TMBIJ0_F0T_Motherboard_J_brd_V01_OCP.brd

C1265  Q_CAP  1UF 6.3V 10% EMPTY  pkg 0402  page 189 : A = P1V8_PCH_PLL_AUX ; B = GND
R4475  Q_RES  1 1% CHIP  pkg 0603LF  page 211 : A = P3V3_9ZXL045 ; B = P3V3_9ZXL045_VDDR
C98  Q_CAP  10UF 16V 10% X6S  pkg C0805  page 105 : A = P12V_S3_AUX_CPU1_NVDIMM ; B = GND

(kicad_pcb
	(version 20260206)
	(generator "pcbnew")
	(generator_version "10.0")
	(general
		(thickness 1.6)
		(legacy_teardrops no)
	)
	(paper "A4")
	(title_block
		(title "03242023_DA0F0TMBIJ0_F0T_Motherboard_J_brd_V01_OCP.brd")
		(comment 1 "Grand Teton / footprints 4946-4948 of 6105")
	)
	(layers
		(0 "F.Cu" signal "TOP")
		(4 "In1.Cu" signal "GND")
		(6 "In2.Cu" signal "IN1")
		(8 "In3.Cu" signal "GND1")
		(10 "In4.Cu" signal "IN2")
		(12 "In5.Cu" signal "GND2")
		(14 "In6.Cu" signal "IN3")
		(16 "In7.Cu" signal "GND3")
		(18 "In8.Cu" signal "VCC")
		(20 "In9.Cu" signal "VCC1")
		(22 "In10.Cu" signal "GND4")
		(24 "In11.Cu" signal "IN4")
		(26 "In12.Cu" signal "GND5")
		(28 "In13.Cu" signal "IN5")
		(30 "In14.Cu" signal "GND6")
		(32 "In15.Cu" signal "IN6")
		(34 "In16.Cu" signal "GND7")
		(2 "B.Cu" signal "BOTTOM")
		(9 "F.Adhes" user "F.Adhesive")
		(11 "B.Adhes" user "B.Adhesive")
		(13 "F.Paste" user "Package Geometry/Pastemask Top")
		(15 "B.Paste" user "Package Geometry/Pastemask Bottom")
		(5 "F.SilkS" user "Ref Des/Silkscreen Top")
		(7 "B.SilkS" user "Ref Des/Silkscreen Bottom")
		(1 "F.Mask" user "Board Geometry/Soldermask Top")
		(3 "B.Mask" user "Board Geometry/Soldermask Bottom")
		(17 "Dwgs.User" user "User.Drawings")
		(19 "Cmts.User" user "User.Comments")
		(21 "Eco1.User" user "User.Eco1")
		(23 "Eco2.User" user "User.Eco2")
		(25 "Edge.Cuts" user "Board Geometry/Outline")
		(27 "Margin" user)
		(31 "F.CrtYd" user "Package Geometry/Place Bound Top")
		(29 "B.CrtYd" user "Package Geometry/Place Bound Bottom")
		(35 "F.Fab" user "Ref Des/Assembly Top")
		(33 "B.Fab" user "Ref Des/Assembly Bottom")
	)
	(footprint ""
		(layer "B.Cu")
		(at 108.42117 -418.336222 180)
		(property "Reference" "R4475"
			(at 0 0 0)
			(layer "B.SilkS")
			(hide yes)
			(effects
				(font
					(size 1.27 1.27)
				)
				(justify mirror)
			)
		)
		(property "Value" ""
			(at 0 0 0)
			(layer "B.Fab")
			(effects
				(font
					(size 1.27 1.27)
				)
				(justify mirror)
			)
		)
		(duplicate_pad_numbers_are_jumpers no)
		(fp_line
			(start 1.2954 0.5842)
			(end 1.2954 -0.5842)
			(stroke
				(width 0.1524)
				(type default)
			)
			(layer "B.SilkS")
		)
		(fp_line
			(start 1.2954 -0.5842)
			(end -1.2954 -0.5842)
			(stroke
				(width 0.1524)
				(type default)
			)
			(layer "B.SilkS")
		)
		(fp_line
			(start -1.2954 0.5842)
			(end 1.2954 0.5842)
			(stroke
				(width 0.1524)
				(type default)
			)
			(layer "B.SilkS")
		)
		(fp_line
			(start -1.2954 -0.5842)
			(end -1.2954 0.5842)
			(stroke
				(width 0.1524)
				(type default)
			)
			(layer "B.SilkS")
		)
		(fp_line
			(start 1.1938 0.4064)
			(end 1.1938 -0.406654)
			(stroke
				(width 0.1)
				(type default)
			)
			(layer "B.Fab")
		)
		(fp_line
			(start 1.1938 -0.406654)
			(end 0.8636 -0.406654)
			(stroke
				(width 0.1)
				(type default)
			)
			(layer "B.Fab")
		)
		(fp_line
			(start 0.8636 0.4572)
			(end 0.8636 0.4318)
			(stroke
				(width 0.1)
				(type default)
			)
			(layer "B.Fab")
		)
		(fp_line
			(start 0.8636 0.4318)
			(end 0.8636 0.4064)
			(stroke
				(width 0.1)
				(type default)
			)
			(layer "B.Fab")
		)
		(fp_line
			(start 0.8636 0.4064)
			(end 1.1938 0.4064)
			(stroke
				(width 0.1)
				(type default)
			)
			(layer "B.Fab")
		)
		(fp_line
			(start 0.8636 -0.406654)
			(end 0.8636 -0.4572)
			(stroke
				(width 0.1)
				(type default)
			)
			(layer "B.Fab")
		)
		(fp_line
			(start 0.8636 -0.4572)
			(end -0.8636 -0.4572)
			(stroke
				(width 0.1)
				(type default)
			)
			(layer "B.Fab")
		)
		(fp_line
			(start -0.8636 0.4572)
			(end 0.8636 0.4572)
			(stroke
				(width 0.1)
				(type default)
			)
			(layer "B.Fab")
		)
		(fp_line
			(start -0.8636 0.4064)
			(end -0.8636 0.4572)
			(stroke
				(width 0.1)
				(type default)
			)
			(layer "B.Fab")
		)
		(fp_line
			(start -0.8636 -0.406654)
			(end -1.1938 -0.406654)
			(stroke
				(width 0.1)
				(type default)
			)
			(layer "B.Fab")
		)
		(fp_line
			(start -0.8636 -0.4572)
			(end -0.8636 -0.406654)
			(stroke
				(width 0.1)
				(type default)
			)
			(layer "B.Fab")
		)
		(fp_line
			(start -1.1938 0.4064)
			(end -0.8636 0.4064)
			(stroke
				(width 0.1)
				(type default)
			)
			(layer "B.Fab")
		)
		(fp_line
			(start -1.1938 -0.406654)
			(end -1.1938 0.4064)
			(stroke
				(width 0.1)
				(type default)
			)
			(layer "B.Fab")
		)
		(pad "1" smd rect
			(at 0.7366 0 90)
			(size 0.7112 0.8128)
			(layers "B.Cu" "B.Mask" "B.Paste")
			(net "P3V3_9ZXL045")
		)
		(pad "2" smd rect
			(at -0.7366 0 90)
			(size 0.7112 0.8128)
			(layers "B.Cu" "B.Mask" "B.Paste")
			(net "P3V3_9ZXL045_VDDR")
		)
	)
	(footprint ""
		(layer "B.Cu")
		(at 341.125048 -52.080922 -90)
		(property "Reference" "C1265"
			(at 0 0 90)
			(layer "B.SilkS")
			(hide yes)
			(effects
				(font
					(size 1.27 1.27)
				)
				(justify mirror)
			)
		)
		(property "Value" ""
			(at 0 0 90)
			(layer "B.Fab")
			(effects
				(font
					(size 1.27 1.27)
				)
				(justify mirror)
			)
		)
		(duplicate_pad_numbers_are_jumpers no)
		(fp_line
			(start -0.7874 0.4064)
			(end 0.7874 0.4064)
			(stroke
				(width 0.1524)
				(type default)
			)
			(layer "B.SilkS")
		)
		(fp_line
			(start 0.7874 0.4064)
			(end 0.7874 -0.4064)
			(stroke
				(width 0.1524)
				(type default)
			)
			(layer "B.SilkS")
		)
		(fp_line
			(start -0.7874 -0.4064)
			(end -0.7874 0.4064)
			(stroke
				(width 0.1524)
				(type default)
			)
			(layer "B.SilkS")
		)
		(fp_line
			(start 0.7874 -0.4064)
			(end -0.7874 -0.4064)
			(stroke
				(width 0.1524)
				(type default)
			)
			(layer "B.SilkS")
		)
		(fp_line
			(start -0.67945 0.3048)
			(end -0.120396 0.3048)
			(stroke
				(width 0.1)
				(type default)
			)
			(layer "B.Fab")
		)
		(fp_line
			(start -0.120396 0.3048)
			(end -0.120396 0.2794)
			(stroke
				(width 0.1)
				(type default)
			)
			(layer "B.Fab")
		)
		(fp_line
			(start 0.12065 0.3048)
			(end 0.67945 0.3048)
			(stroke
				(width 0.1)
				(type default)
			)
			(layer "B.Fab")
		)
		(fp_line
			(start 0.67945 0.3048)
			(end 0.67945 -0.305054)
			(stroke
				(width 0.1)
				(type default)
			)
			(layer "B.Fab")
		)
		(fp_line
			(start -0.120396 0.2794)
			(end 0.12065 0.2794)
			(stroke
				(width 0.1)
				(type default)
			)
			(layer "B.Fab")
		)
		(fp_line
			(start 0.12065 0.2794)
			(end 0.12065 0.3048)
			(stroke
				(width 0.1)
				(type default)
			)
			(layer "B.Fab")
		)
		(fp_line
			(start -0.12065 -0.2794)
			(end -0.12065 -0.3048)
			(stroke
				(width 0.1)
				(type default)
			)
			(layer "B.Fab")
		)
		(fp_line
			(start 0.12065 -0.2794)
			(end -0.12065 -0.2794)
			(stroke
				(width 0.1)
				(type default)
			)
			(layer "B.Fab")
		)
		(fp_line
			(start -0.67945 -0.3048)
			(end -0.67945 0.3048)
			(stroke
				(width 0.1)
				(type default)
			)
			(layer "B.Fab")
		)
		(fp_line
			(start -0.12065 -0.3048)
			(end -0.67945 -0.3048)
			(stroke
				(width 0.1)
				(type default)
			)
			(layer "B.Fab")
		)
		(fp_line
			(start 0.12065 -0.305054)
			(end 0.12065 -0.2794)
			(stroke
				(width 0.1)
				(type default)
			)
			(layer "B.Fab")
		)
		(fp_line
			(start 0.67945 -0.305054)
			(end 0.12065 -0.305054)
			(stroke
				(width 0.1)
				(type default)
			)
			(layer "B.Fab")
		)
		(pad "1" smd circle
			(at 0.40005 0 90)
			(size 0 0)
			(layers "B.Cu" "B.Mask" "B.Paste")
			(net "P1V8_PCH_PLL_AUX")
		)
		(pad "2" smd circle
			(at -0.40005 0 90)
			(size 0 0)
			(layers "B.Cu" "B.Mask" "B.Paste")
			(net "GND")
		)
	)
	(footprint ""
		(layer "B.Cu")
		(at 15.696946 -321.554856 -90)
		(property "Reference" "C98"
			(at 0 0 90)
			(layer "B.SilkS")
			(hide yes)
			(effects
				(font
					(size 1.27 1.27)
				)
				(justify mirror)
			)
		)
		(property "Value" ""
			(at 0 0 90)
			(layer "B.Fab")
			(effects
				(font
					(size 1.27 1.27)
				)
				(justify mirror)
			)
		)
		(duplicate_pad_numbers_are_jumpers no)
		(fp_line
			(start -1.524 0.762)
			(end 1.524 0.762)
			(stroke
				(width 0.1524)
				(type default)
			)
			(layer "B.SilkS")
		)
		(fp_line
			(start 1.524 0.762)
			(end 1.524 -0.762)
			(stroke
				(width 0.1524)
				(type default)
			)
			(layer "B.SilkS")
		)
		(fp_line
			(start -1.524 -0.762)
			(end -1.524 0.762)
			(stroke
				(width 0.1524)
				(type default)
			)
			(layer "B.SilkS")
		)
		(fp_line
			(start 1.524 -0.762)
			(end -1.524 -0.762)
			(stroke
				(width 0.1524)
				(type default)
			)
			(layer "B.SilkS")
		)
		(fp_line
			(start -1.1049 0.724916)
			(end -1.1049 -0.724916)
			(stroke
				(width 0.1)
				(type default)
			)
			(layer "B.Fab")
		)
		(fp_line
			(start 1.1049 0.724916)
			(end -1.1049 0.724916)
			(stroke
				(width 0.1)
				(type default)
			)
			(layer "B.Fab")
		)
		(fp_line
			(start -1.1049 -0.724916)
			(end 1.1049 -0.724916)
			(stroke
				(width 0.1)
				(type default)
			)
			(layer "B.Fab")
		)
		(fp_line
			(start 1.1049 -0.724916)
			(end 1.1049 0.724916)
			(stroke
				(width 0.1)
				(type default)
			)
			(layer "B.Fab")
		)
		(pad "1" smd rect
			(at 0.889 0 270)
			(size 1.016 1.27)
			(layers "B.Cu" "B.Mask" "B.Paste")
			(net "P12V_S3_AUX_CPU1_NVDIMM")
		)
		(pad "2" smd rect
			(at -0.889 0 270)
			(size 1.016 1.27)
			(layers "B.Cu" "B.Mask" "B.Paste")
			(net "GND")
		)
	)
)
